(kicad_pcb
	(version 20260206)
	(generator "pcbnew")
	(generator_version "10.0")
	(general
		(thickness 1.6)
		(legacy_teardrops no)
	)
	(paper "A4")
	(title_block
		(title "Bryce Canyon_R.DPB_16317-1_OCP.brd")
		(comment 1 "Bryce Canyon / footprints 300-306 of 2099")
	)
	(layers
		(0 "F.Cu" signal "TOP")
		(4 "In1.Cu" signal "L2GND")
		(6 "In2.Cu" signal "L3")
		(8 "In3.Cu" signal "L4VCC")
		(10 "In4.Cu" signal "L5VCC")
		(12 "In5.Cu" signal "L6")
		(14 "In6.Cu" signal "L7GND")
		(2 "B.Cu" signal "BOTTOM")
		(9 "F.Adhes" user "F.Adhesive")
		(11 "B.Adhes" user "B.Adhesive")
		(13 "F.Paste" user "Package Geometry/Pastemask Top")
		(15 "B.Paste" user "Package Geometry/Pastemask Bottom")
		(5 "F.SilkS" user "Ref Des/Silkscreen Top")
		(7 "B.SilkS" user "Ref Des/Silkscreen Bottom")
		(1 "F.Mask" user "Board Geometry/Soldermask Top")
		(3 "B.Mask" user "Board Geometry/Soldermask Bottom")
		(17 "Dwgs.User" user "User.Drawings")
		(19 "Cmts.User" user "User.Comments")
		(21 "Eco1.User" user "User.Eco1")
		(23 "Eco2.User" user "User.Eco2")
		(25 "Edge.Cuts" user "Board Geometry/Outline")
		(27 "Margin" user)
		(31 "F.CrtYd" user "Package Geometry/Place Bound Top")
		(29 "B.CrtYd" user "Package Geometry/Place Bound Bottom")
		(35 "F.Fab" user "Ref Des/Assembly Top")
		(33 "B.Fab" user "Ref Des/Assembly Bottom")
	)
	(footprint ""
		(layer "F.Cu")
		(at 254.2413 -214.31504)
		(property "Reference" "R118"
			(at 0 0 0)
			(layer "F.SilkS")
			(hide yes)
			(effects
				(font
					(size 1.27 1.27)
				)
			)
		)
		(property "Value" "0R2J-2-GP"
			(at 0.064008 -3.993896 0)
			(unlocked yes)
			(layer "F.Fab")
			(hide yes)
			(effects
				(font
					(size 1.016 1.016)
					(thickness 0.1524)
				)
			)
		)
		(property "Device Type" "R402H16"
			(at 0.064008 -5.517896 0)
			(unlocked yes)
			(layer "F.Fab")
			(hide yes)
			(effects
				(font
					(size 1.016 1.016)
					(thickness 0.1524)
				)
			)
		)
		(duplicate_pad_numbers_are_jumpers no)
		(fp_line
			(start -0.508 -0.9398)
			(end -0.508 0.9398)
			(stroke
				(width 0.1524)
				(type default)
			)
			(layer "F.SilkS")
		)
		(fp_line
			(start 0.508 -0.9398)
			(end -0.508 -0.9398)
			(stroke
				(width 0.1524)
				(type default)
			)
			(layer "F.SilkS")
		)
		(fp_rect
			(start -0.508 0.9398)
			(end 0.508 -0.9398)
			(stroke
				(width 0)
				(type default)
			)
			(fill no)
			(layer "F.CrtYd")
		)
		(fp_rect
			(start -0.508 0.9398)
			(end 0.508 -0.9398)
			(stroke
				(width 0)
				(type default)
			)
			(fill no)
			(layer "F.Fab")
		)
		(pad "1" smd custom
			(at 0 -0.4445)
			(size 0.1397 0.1397)
			(layers "F.Cu" "F.Mask" "F.Paste")
			(net "VOL_SEN_SDA")
			(options
				(clearance outline)
				(anchor circle)
			)
			(primitives
				(gr_poly
					(pts
						(arc
							(start -0.1778 -0.2794)
							(mid -0.249642 -0.249642)
							(end -0.2794 -0.1778)
						)
						(arc
							(start -0.2794 0.1778)
							(mid -0.249642 0.249642)
							(end -0.1778 0.2794)
						)
						(arc
							(start 0.1778 0.2794)
							(mid 0.249642 0.249642)
							(end 0.2794 0.1778)
						)
						(arc
							(start 0.2794 -0.1778)
							(mid 0.249642 -0.249642)
							(end 0.1778 -0.2794)
						)
					)
					(width 0)
					(fill yes)
				)
			)
		)
		(pad "2" smd custom
			(at 0 0.4445)
			(size 0.1397 0.1397)
			(layers "F.Cu" "F.Mask" "F.Paste")
			(net "I2C_DPB_B_SDA_BUF")
			(options
				(clearance outline)
				(anchor circle)
			)
			(primitives
				(gr_poly
					(pts
						(arc
							(start -0.1778 -0.2794)
							(mid -0.249642 -0.249642)
							(end -0.2794 -0.1778)
						)
						(arc
							(start -0.2794 0.1778)
							(mid -0.249642 0.249642)
							(end -0.1778 0.2794)
						)
						(arc
							(start 0.1778 0.2794)
							(mid 0.249642 0.249642)
							(end 0.2794 0.1778)
						)
						(arc
							(start 0.2794 -0.1778)
							(mid 0.249642 -0.249642)
							(end 0.1778 -0.2794)
						)
					)
					(width 0)
					(fill yes)
				)
			)
		)
	)
	(footprint ""
		(layer "F.Cu")
		(at 441.349892 -180.399944)
		(property "Reference" "LED11"
			(at 0 0 0)
			(layer "F.SilkS")
			(hide yes)
			(effects
				(font
					(size 1.27 1.27)
				)
			)
		)
		(property "Value" "LED-BY-19-GP"
			(at -2.132076 1.414018 0)
			(unlocked yes)
			(layer "F.Fab")
			(hide yes)
			(effects
				(font
					(size 1.016 1.016)
					(thickness 0.1524)
				)
			)
		)
		(property "Device Type" "LED-1615-4PH26"
			(at -2.132076 -0.109982 0)
			(unlocked yes)
			(layer "F.Fab")
			(hide yes)
			(effects
				(font
					(size 1.016 1.016)
					(thickness 0.1524)
				)
			)
		)
		(duplicate_pad_numbers_are_jumpers no)
		(fp_line
			(start -1.2954 0.254)
			(end -1.2954 1.6002)
			(stroke
				(width 0.508)
				(type default)
			)
			(layer "F.SilkS")
		)
		(fp_line
			(start -1.2954 1.6002)
			(end 1.2954 1.6002)
			(stroke
				(width 0.508)
				(type default)
			)
			(layer "F.SilkS")
		)
		(fp_line
			(start -1.1176 -1.4224)
			(end 1.1176 -1.4224)
			(stroke
				(width 0.1524)
				(type default)
			)
			(layer "F.SilkS")
		)
		(fp_line
			(start -1.1176 1.4224)
			(end -1.1176 -1.4224)
			(stroke
				(width 0.1524)
				(type default)
			)
			(layer "F.SilkS")
		)
		(fp_line
			(start 1.1176 -1.4224)
			(end 1.1176 1.4224)
			(stroke
				(width 0.1524)
				(type default)
			)
			(layer "F.SilkS")
		)
		(fp_line
			(start 1.1176 1.4224)
			(end -1.1176 1.4224)
			(stroke
				(width 0.1524)
				(type default)
			)
			(layer "F.SilkS")
		)
		(fp_line
			(start 1.2954 1.6002)
			(end 1.2954 0.254)
			(stroke
				(width 0.508)
				(type default)
			)
			(layer "F.SilkS")
		)
		(fp_rect
			(start -0.7493 0.8001)
			(end 0.7493 -0.8001)
			(stroke
				(width 0)
				(type default)
			)
			(fill no)
			(layer "F.CrtYd")
		)
		(fp_poly
			(pts
				(xy -1.3716 1.6764) (xy -1.3716 -1.6764) (xy 1.3716 -1.6764) (xy 1.3716 0.0635) (xy 0.7493 0.0635)
				(xy 0.7493 -0.8001) (xy -0.7493 -0.8001) (xy -0.7493 0.8001) (xy 0.7493 0.8001) (xy 0.7493 0.0762)
				(xy 1.3716 0.0762) (xy 1.3716 1.6764)
			)
			(stroke
				(width 0)
				(type default)
			)
			(fill no)
			(layer "F.CrtYd")
		)
		(fp_rect
			(start -1.3716 1.6764)
			(end 1.3716 -1.6764)
			(stroke
				(width 0)
				(type default)
			)
			(fill no)
			(layer "F.Fab")
		)
		(pad "1" smd rect
			(at 0.50038 -0.73025)
			(size 0.7112 0.8636)
			(layers "F.Cu" "F.Mask" "F.Paste")
			(net "DRV_ACT_10")
		)
		(pad "2" smd rect
			(at -0.50038 -0.73025)
			(size 0.7112 0.8636)
			(layers "F.Cu" "F.Mask" "F.Paste")
			(net "FLT_HDD10")
		)
		(pad "3" smd rect
			(at 0.50038 0.73025)
			(size 0.7112 0.8636)
			(layers "F.Cu" "F.Mask" "F.Paste")
			(net "DRV_ACT_10_N")
		)
		(pad "4" smd rect
			(at -0.50038 0.73025)
			(size 0.7112 0.8636)
			(layers "F.Cu" "F.Mask" "F.Paste")
			(net "FLT_HDD10_N")
		)
	)
	(footprint ""
		(layer "F.Cu")
		(at 143.999966 -65.39992)
		(property "Reference" "LED17"
			(at 0 0 0)
			(layer "F.SilkS")
			(hide yes)
			(effects
				(font
					(size 1.27 1.27)
				)
			)
		)
		(property "Value" "LED-BY-19-GP"
			(at -2.132076 1.414018 0)
			(unlocked yes)
			(layer "F.Fab")
			(hide yes)
			(effects
				(font
					(size 1.016 1.016)
					(thickness 0.1524)
				)
			)
		)
		(property "Device Type" "LED-1615-4PH26"
			(at -2.132076 -0.109982 0)
			(unlocked yes)
			(layer "F.Fab")
			(hide yes)
			(effects
				(font
					(size 1.016 1.016)
					(thickness 0.1524)
				)
			)
		)
		(duplicate_pad_numbers_are_jumpers no)
		(fp_line
			(start -1.2954 0.254)
			(end -1.2954 1.6002)
			(stroke
				(width 0.508)
				(type default)
			)
			(layer "F.SilkS")
		)
		(fp_line
			(start -1.2954 1.6002)
			(end 1.2954 1.6002)
			(stroke
				(width 0.508)
				(type default)
			)
			(layer "F.SilkS")
		)
		(fp_line
			(start -1.1176 -1.4224)
			(end 1.1176 -1.4224)
			(stroke
				(width 0.1524)
				(type default)
			)
			(layer "F.SilkS")
		)
		(fp_line
			(start -1.1176 1.4224)
			(end -1.1176 -1.4224)
			(stroke
				(width 0.1524)
				(type default)
			)
			(layer "F.SilkS")
		)
		(fp_line
			(start 1.1176 -1.4224)
			(end 1.1176 1.4224)
			(stroke
				(width 0.1524)
				(type default)
			)
			(layer "F.SilkS")
		)
		(fp_line
			(start 1.1176 1.4224)
			(end -1.1176 1.4224)
			(stroke
				(width 0.1524)
				(type default)
			)
			(layer "F.SilkS")
		)
		(fp_line
			(start 1.2954 1.6002)
			(end 1.2954 0.254)
			(stroke
				(width 0.508)
				(type default)
			)
			(layer "F.SilkS")
		)
		(fp_rect
			(start -0.7493 0.8001)
			(end 0.7493 -0.8001)
			(stroke
				(width 0)
				(type default)
			)
			(fill no)
			(layer "F.CrtYd")
		)
		(fp_poly
			(pts
				(xy -1.3716 1.6764) (xy -1.3716 -1.6764) (xy 1.3716 -1.6764) (xy 1.3716 0.0635) (xy 0.7493 0.0635)
				(xy 0.7493 -0.8001) (xy -0.7493 -0.8001) (xy -0.7493 0.8001) (xy 0.7493 0.8001) (xy 0.7493 0.0762)
				(xy 1.3716 0.0762) (xy 1.3716 1.6764)
			)
			(stroke
				(width 0)
				(type default)
			)
			(fill no)
			(layer "F.CrtYd")
		)
		(fp_rect
			(start -1.3716 1.6764)
			(end 1.3716 -1.6764)
			(stroke
				(width 0)
				(type default)
			)
			(fill no)
			(layer "F.Fab")
		)
		(pad "1" smd rect
			(at 0.50038 -0.73025)
			(size 0.7112 0.8636)
			(layers "F.Cu" "F.Mask" "F.Paste")
			(net "DRV_ACT_16")
		)
		(pad "2" smd rect
			(at -0.50038 -0.73025)
			(size 0.7112 0.8636)
			(layers "F.Cu" "F.Mask" "F.Paste")
			(net "FLT_HDD16")
		)
		(pad "3" smd rect
			(at 0.50038 0.73025)
			(size 0.7112 0.8636)
			(layers "F.Cu" "F.Mask" "F.Paste")
			(net "DRV_ACT_16_N")
		)
		(pad "4" smd rect
			(at -0.50038 0.73025)
			(size 0.7112 0.8636)
			(layers "F.Cu" "F.Mask" "F.Paste")
			(net "FLT_HDD16_N")
		)
	)
	(footprint ""
		(layer "F.Cu")
		(at 438.643776 -217.413586 -90)
		(property "Reference" "R306"
			(at 0 0 270)
			(layer "F.SilkS")
			(hide yes)
			(effects
				(font
					(size 1.27 1.27)
				)
			)
		)
		(property "Value" "4K7R2F-GP"
			(at 0.064008 -3.993896 270)
			(unlocked yes)
			(layer "F.Fab")
			(hide yes)
			(effects
				(font
					(size 1.016 1.016)
					(thickness 0.1524)
				)
			)
		)
		(property "Device Type" "R402H16"
			(at 0.064008 -5.517896 270)
			(unlocked yes)
			(layer "F.Fab")
			(hide yes)
			(effects
				(font
					(size 1.016 1.016)
					(thickness 0.1524)
				)
			)
		)
		(duplicate_pad_numbers_are_jumpers no)
		(fp_line
			(start -0.508 -0.9398)
			(end -0.508 0.9398)
			(stroke
				(width 0.1524)
				(type default)
			)
			(layer "F.SilkS")
		)
		(fp_line
			(start 0.508 -0.9398)
			(end -0.508 -0.9398)
			(stroke
				(width 0.1524)
				(type default)
			)
			(layer "F.SilkS")
		)
		(fp_rect
			(start -0.508 0.9398)
			(end 0.508 -0.9398)
			(stroke
				(width 0)
				(type default)
			)
			(fill no)
			(layer "F.CrtYd")
		)
		(fp_rect
			(start -0.508 0.9398)
			(end 0.508 -0.9398)
			(stroke
				(width 0)
				(type default)
			)
			(fill no)
			(layer "F.Fab")
		)
		(pad "1" smd custom
			(at 0 -0.4445 270)
			(size 0.1397 0.1397)
			(layers "F.Cu" "F.Mask" "F.Paste")
			(net "DRIVE_B_10_FLT_LED")
			(options
				(clearance outline)
				(anchor circle)
			)
			(primitives
				(gr_poly
					(pts
						(arc
							(start -0.1778 -0.2794)
							(mid -0.249642 -0.249642)
							(end -0.2794 -0.1778)
						)
						(arc
							(start -0.2794 0.1778)
							(mid -0.249642 0.249642)
							(end -0.1778 0.2794)
						)
						(arc
							(start 0.1778 0.2794)
							(mid 0.249642 0.249642)
							(end 0.2794 0.1778)
						)
						(arc
							(start 0.2794 -0.1778)
							(mid 0.249642 -0.249642)
							(end 0.1778 -0.2794)
						)
					)
					(width 0)
					(fill yes)
				)
			)
		)
		(pad "2" smd custom
			(at 0 0.4445 270)
			(size 0.1397 0.1397)
			(layers "F.Cu" "F.Mask" "F.Paste")
			(net "GND")
			(options
				(clearance outline)
				(anchor circle)
			)
			(primitives
				(gr_poly
					(pts
						(arc
							(start -0.1778 -0.2794)
							(mid -0.249642 -0.249642)
							(end -0.2794 -0.1778)
						)
						(arc
							(start -0.2794 0.1778)
							(mid -0.249642 0.249642)
							(end -0.1778 0.2794)
						)
						(arc
							(start 0.1778 0.2794)
							(mid 0.249642 0.249642)
							(end 0.2794 0.1778)
						)
						(arc
							(start 0.2794 -0.1778)
							(mid 0.249642 -0.249642)
							(end 0.1778 -0.2794)
						)
					)
					(width 0)
					(fill yes)
				)
			)
		)
	)
	(footprint ""
		(layer "F.Cu")
		(at 177.8 -32.004 -90)
		(property "Reference" "C408"
			(at 0 0 270)
			(layer "F.SilkS")
			(hide yes)
			(effects
				(font
					(size 1.27 1.27)
				)
			)
		)
		(property "Value" "SC10U16V6KX-2GP"
			(at -0.0762 -5.1308 270)
			(unlocked yes)
			(layer "F.Fab")
			(hide yes)
			(effects
				(font
					(size 1.016 1.016)
					(thickness 0.1524)
				)
			)
		)
		(property "Device Type" "C1206H71"
			(at -0.127 -6.6548 270)
			(unlocked yes)
			(layer "F.Fab")
			(hide yes)
			(effects
				(font
					(size 1.016 1.016)
					(thickness 0.1524)
				)
			)
		)
		(duplicate_pad_numbers_are_jumpers no)
		(fp_line
			(start -1.016 2.2352)
			(end -1.016 0.8382)
			(stroke
				(width 0.1524)
				(type default)
			)
			(layer "F.SilkS")
		)
		(fp_line
			(start 1.016 2.2352)
			(end -1.016 2.2352)
			(stroke
				(width 0.1524)
				(type default)
			)
			(layer "F.SilkS")
		)
		(fp_line
			(start 1.016 0.8382)
			(end 1.016 2.2352)
			(stroke
				(width 0.1524)
				(type default)
			)
			(layer "F.SilkS")
		)
		(fp_line
			(start -1.016 -0.8382)
			(end -1.016 -2.2352)
			(stroke
				(width 0.1524)
				(type default)
			)
			(layer "F.SilkS")
		)
		(fp_line
			(start -1.016 -2.2352)
			(end 1.016 -2.2352)
			(stroke
				(width 0.1524)
				(type default)
			)
			(layer "F.SilkS")
		)
		(fp_line
			(start 1.016 -2.2352)
			(end 1.016 -0.8382)
			(stroke
				(width 0.1524)
				(type default)
			)
			(layer "F.SilkS")
		)
		(fp_rect
			(start -1.0922 2.3114)
			(end 1.0922 -2.3114)
			(stroke
				(width 0)
				(type default)
			)
			(fill no)
			(layer "F.CrtYd")
		)
		(fp_poly
			(pts
				(xy 1.0922 -2.3114) (xy 1.0922 2.3114) (xy -1.0922 2.3114) (xy -1.0922 -2.3114)
			)
			(stroke
				(width 0)
				(type default)
			)
			(fill no)
			(layer "F.Fab")
		)
		(pad "1" smd rect
			(at 0 -1.397 270)
			(size 1.651 1.27)
			(layers "F.Cu" "F.Mask" "F.Paste")
			(net "P5V_HDD29")
		)
		(pad "2" smd rect
			(at 0 1.397 270)
			(size 1.651 1.27)
			(layers "F.Cu" "F.Mask" "F.Paste")
			(net "GND")
		)
	)
	(footprint ""
		(layer "F.Cu")
		(at 65.83553 -244.990874 90)
		(property "Reference" "VIA3"
			(at 0 0 90)
			(layer "F.SilkS")
			(hide yes)
			(effects
				(font
					(size 1.27 1.27)
				)
			)
		)
		(property "Value" "100OHM-8L-2D36MM-L18-GP"
			(at 3.8989 0.5715 90)
			(unlocked yes)
			(layer "F.Fab")
			(hide yes)
			(effects
				(font
					(size 1.016 1.016)
					(thickness 0.1524)
				)
			)
		)
		(property "Device Type" "VIA-PCIE-4P-414097"
			(at 3.8989 -0.9525 90)
			(unlocked yes)
			(layer "F.Fab")
			(hide yes)
			(effects
				(font
					(size 1.016 1.016)
					(thickness 0.1524)
				)
			)
		)
		(duplicate_pad_numbers_are_jumpers no)
		(fp_rect
			(start -2.0701 0.4826)
			(end 2.0701 -0.4826)
			(stroke
				(width 0)
				(type default)
			)
			(fill no)
			(layer "F.CrtYd")
		)
		(fp_rect
			(start -2.0701 0.4826)
			(end 2.0701 -0.4826)
			(stroke
				(width 0)
				(type default)
			)
			(fill no)
			(layer "F.Fab")
		)
		(pad "1" thru_hole circle
			(at -1.5875 0 90)
			(size 0.508 0.508)
			(drill 0.254)
			(layers "*.Cu" "*.Mask")
			(remove_unused_layers no)
			(net "GND")
			(clearance 0.2286)
			(thermal_gap 0.2286)
		)
		(pad "2" thru_hole circle
			(at -0.5715 0 90)
			(size 0.508 0.508)
			(drill 0.254)
			(layers "*.Cu" "*.Mask")
			(remove_unused_layers no)
			(net "PHY_SCC_B_TO_DRV_B_1_DP")
			(clearance 0.2286)
			(thermal_gap 0.2286)
		)
		(pad "3" thru_hole circle
			(at 0.5715 0 90)
			(size 0.508 0.508)
			(drill 0.254)
			(layers "*.Cu" "*.Mask")
			(remove_unused_layers no)
			(net "PHY_SCC_B_TO_DRV_B_1_DN")
			(clearance 0.2286)
			(thermal_gap 0.2286)
		)
		(pad "4" thru_hole circle
			(at 1.5875 0 90)
			(size 0.508 0.508)
			(drill 0.254)
			(layers "*.Cu" "*.Mask")
			(remove_unused_layers no)
			(net "GND")
			(clearance 0.2286)
			(thermal_gap 0.2286)
		)
	)
	(footprint ""
		(layer "F.Cu")
		(at 41.242996 -363.1438)
		(property "Reference" "R928"
			(at 0 0 0)
			(layer "F.SilkS")
			(hide yes)
			(effects
				(font
					(size 1.27 1.27)
				)
			)
		)
		(property "Value" "100KR2F-L1-GP"
			(at 0.064008 -3.993896 0)
			(unlocked yes)
			(layer "F.Fab")
			(hide yes)
			(effects
				(font
					(size 1.016 1.016)
					(thickness 0.1524)
				)
			)
		)
		(property "Device Type" "R402H16"
			(at 0.064008 -5.517896 0)
			(unlocked yes)
			(layer "F.Fab")
			(hide yes)
			(effects
				(font
					(size 1.016 1.016)
					(thickness 0.1524)
				)
			)
		)
		(duplicate_pad_numbers_are_jumpers no)
		(fp_line
			(start -0.508 -0.9398)
			(end -0.508 0.9398)
			(stroke
				(width 0.1524)
				(type default)
			)
			(layer "F.SilkS")
		)
		(fp_line
			(start 0.508 -0.9398)
			(end -0.508 -0.9398)
			(stroke
				(width 0.1524)
				(type default)
			)
			(layer "F.SilkS")
		)
		(fp_rect
			(start -0.508 0.9398)
			(end 0.508 -0.9398)
			(stroke
				(width 0)
				(type default)
			)
			(fill no)
			(layer "F.CrtYd")
		)
		(fp_rect
			(start -0.508 0.9398)
			(end 0.508 -0.9398)
			(stroke
				(width 0)
				(type default)
			)
			(fill no)
			(layer "F.Fab")
		)
		(pad "1" smd custom
			(at 0 -0.4445)
			(size 0.1397 0.1397)
			(layers "F.Cu" "F.Mask" "F.Paste")
			(net "SCC_B_FULL_PWR_EN")
			(options
				(clearance outline)
				(anchor circle)
			)
			(primitives
				(gr_poly
					(pts
						(arc
							(start -0.1778 -0.2794)
							(mid -0.249642 -0.249642)
							(end -0.2794 -0.1778)
						)
						(arc
							(start -0.2794 0.1778)
							(mid -0.249642 0.249642)
							(end -0.1778 0.2794)
						)
						(arc
							(start 0.1778 0.2794)
							(mid 0.249642 0.249642)
							(end 0.2794 0.1778)
						)
						(arc
							(start 0.2794 -0.1778)
							(mid 0.249642 -0.249642)
							(end 0.1778 -0.2794)
						)
					)
					(width 0)
					(fill yes)
				)
			)
		)
		(pad "2" smd custom
			(at 0 0.4445)
			(size 0.1397 0.1397)
			(layers "F.Cu" "F.Mask" "F.Paste")
			(net "GND")
			(options
				(clearance outline)
				(anchor circle)
			)
			(primitives
				(gr_poly
					(pts
						(arc
							(start -0.1778 -0.2794)
							(mid -0.249642 -0.249642)
							(end -0.2794 -0.1778)
						)
						(arc
							(start -0.2794 0.1778)
							(mid -0.249642 0.249642)
							(end -0.1778 0.2794)
						)
						(arc
							(start 0.1778 0.2794)
							(mid 0.249642 0.249642)
							(end 0.2794 0.1778)
						)
						(arc
							(start 0.2794 -0.1778)
							(mid 0.249642 -0.249642)
							(end 0.1778 -0.2794)
						)
					)
					(width 0)
					(fill yes)
				)
			)
		)
	)
)
